# T6G (Grand Teton) — schematic netlist excerpt (pin names and nets, part order shuffled) for the footprints in the layout excerpt that follows; sources: Cadence DE-HDL packaged netlist, KiCad conversion of 04192023_DAF0TMB3IC0_F0TG_MB_C_brd_V02_OCP.brd

R1644  Q_RES  22 1% CHIP  pkg 0402LF  page 173 : A = JTAG_P1_R_TRST_N ; B = JTAG_CPU1_TRST_N
R4212  Q_RES  0 5% CHIP  pkg 0402LF  page 235 : A = FM_THERMAL_ALERT_N ; B = FM_LM75_3_ALERT_N

(kicad_pcb
	(version 20260206)
	(generator "pcbnew")
	(generator_version "10.0")
	(general
		(thickness 1.6)
		(legacy_teardrops no)
	)
	(paper "A4")
	(title_block
		(title "04192023_DAF0TMB3IC0_F0TG_MB_C_brd_V02_OCP.brd")
		(comment 1 "Grand Teton / footprints 4341-4342 of 8354")
	)
	(layers
		(0 "F.Cu" signal "TOP")
		(4 "In1.Cu" signal "GND")
		(6 "In2.Cu" signal "IN1")
		(8 "In3.Cu" signal "GND1")
		(10 "In4.Cu" signal "IN2")
		(12 "In5.Cu" signal "GND2")
		(14 "In6.Cu" signal "IN3")
		(16 "In7.Cu" signal "GND3")
		(18 "In8.Cu" signal "VCC")
		(20 "In9.Cu" signal "VCC1")
		(22 "In10.Cu" signal "GND4")
		(24 "In11.Cu" signal "IN4")
		(26 "In12.Cu" signal "GND5")
		(28 "In13.Cu" signal "IN5")
		(30 "In14.Cu" signal "GND6")
		(32 "In15.Cu" signal "IN6")
		(34 "In16.Cu" signal "GND7")
		(2 "B.Cu" signal "BOTTOM")
		(9 "F.Adhes" user "F.Adhesive")
		(11 "B.Adhes" user "B.Adhesive")
		(13 "F.Paste" user "Package Geometry/Pastemask Top")
		(15 "B.Paste" user "Package Geometry/Pastemask Bottom")
		(5 "F.SilkS" user "Ref Des/Silkscreen Top")
		(7 "B.SilkS" user "Ref Des/Silkscreen Bottom")
		(1 "F.Mask" user "Board Geometry/Soldermask Top")
		(3 "B.Mask" user "Board Geometry/Soldermask Bottom")
		(17 "Dwgs.User" user "User.Drawings")
		(19 "Cmts.User" user "User.Comments")
		(21 "Eco1.User" user "User.Eco1")
		(23 "Eco2.User" user "User.Eco2")
		(25 "Edge.Cuts" user "Board Geometry/Outline")
		(27 "Margin" user)
		(31 "F.CrtYd" user "Package Geometry/Place Bound Top")
		(29 "B.CrtYd" user "Package Geometry/Place Bound Bottom")
		(35 "F.Fab" user "Ref Des/Assembly Top")
		(33 "B.Fab" user "Ref Des/Assembly Bottom")
	)
	(footprint ""
		(layer "F.Cu")
		(at 106.932222 -15.22349)
		(property "Reference" "R4212"
			(at 0 0 0)
			(layer "F.SilkS")
			(hide yes)
			(effects
				(font
					(size 1.27 1.27)
				)
			)
		)
		(property "Value" ""
			(at 0 0 0)
			(layer "F.Fab")
			(effects
				(font
					(size 1.27 1.27)
				)
			)
		)
		(duplicate_pad_numbers_are_jumpers no)
		(fp_line
			(start -0.7874 -0.4064)
			(end 0.7874 -0.4064)
			(stroke
				(width 0.1524)
				(type default)
			)
			(layer "F.SilkS")
		)
		(fp_line
			(start -0.7874 0.4064)
			(end -0.7874 -0.4064)
			(stroke
				(width 0.1524)
				(type default)
			)
			(layer "F.SilkS")
		)
		(fp_line
			(start 0.7874 -0.4064)
			(end 0.7874 0.4064)
			(stroke
				(width 0.1524)
				(type default)
			)
			(layer "F.SilkS")
		)
		(fp_line
			(start 0.7874 0.4064)
			(end -0.7874 0.4064)
			(stroke
				(width 0.1524)
				(type default)
			)
			(layer "F.SilkS")
		)
		(fp_line
			(start -0.67945 -0.305054)
			(end -0.12065 -0.305054)
			(stroke
				(width 0.1)
				(type default)
			)
			(layer "F.Fab")
		)
		(fp_line
			(start -0.67945 0.3048)
			(end -0.67945 -0.305054)
			(stroke
				(width 0.1)
				(type default)
			)
			(layer "F.Fab")
		)
		(fp_line
			(start -0.12065 -0.305054)
			(end -0.12065 -0.2794)
			(stroke
				(width 0.1)
				(type default)
			)
			(layer "F.Fab")
		)
		(fp_line
			(start -0.12065 -0.2794)
			(end 0.12065 -0.2794)
			(stroke
				(width 0.1)
				(type default)
			)
			(layer "F.Fab")
		)
		(fp_line
			(start -0.12065 0.2794)
			(end -0.12065 0.3048)
			(stroke
				(width 0.1)
				(type default)
			)
			(layer "F.Fab")
		)
		(fp_line
			(start -0.12065 0.3048)
			(end -0.67945 0.3048)
			(stroke
				(width 0.1)
				(type default)
			)
			(layer "F.Fab")
		)
		(fp_line
			(start 0.120396 0.2794)
			(end -0.12065 0.2794)
			(stroke
				(width 0.1)
				(type default)
			)
			(layer "F.Fab")
		)
		(fp_line
			(start 0.120396 0.3048)
			(end 0.120396 0.2794)
			(stroke
				(width 0.1)
				(type default)
			)
			(layer "F.Fab")
		)
		(fp_line
			(start 0.12065 -0.3048)
			(end 0.67945 -0.3048)
			(stroke
				(width 0.1)
				(type default)
			)
			(layer "F.Fab")
		)
		(fp_line
			(start 0.12065 -0.2794)
			(end 0.12065 -0.3048)
			(stroke
				(width 0.1)
				(type default)
			)
			(layer "F.Fab")
		)
		(fp_line
			(start 0.67945 -0.3048)
			(end 0.67945 0.3048)
			(stroke
				(width 0.1)
				(type default)
			)
			(layer "F.Fab")
		)
		(fp_line
			(start 0.67945 0.3048)
			(end 0.120396 0.3048)
			(stroke
				(width 0.1)
				(type default)
			)
			(layer "F.Fab")
		)
		(pad "1" smd circle
			(at -0.40005 0)
			(size 0 0)
			(layers "F.Cu" "F.Mask" "F.Paste")
			(net "FM_THERMAL_ALERT_N")
		)
		(pad "2" smd circle
			(at 0.40005 0)
			(size 0 0)
			(layers "F.Cu" "F.Mask" "F.Paste")
			(net "FM_LM75_3_ALERT_N")
		)
	)
	(footprint ""
		(layer "F.Cu")
		(at 275.14169 -98.355404 180)
		(property "Reference" "R1644"
			(at 0 0 180)
			(layer "F.SilkS")
			(hide yes)
			(effects
				(font
					(size 1.27 1.27)
				)
			)
		)
		(property "Value" ""
			(at 0 0 180)
			(layer "F.Fab")
			(effects
				(font
					(size 1.27 1.27)
				)
			)
		)
		(duplicate_pad_numbers_are_jumpers no)
		(fp_line
			(start 0.7874 0.4064)
			(end -0.7874 0.4064)
			(stroke
				(width 0.1524)
				(type default)
			)
			(layer "F.SilkS")
		)
		(fp_line
			(start 0.7874 -0.4064)
			(end 0.7874 0.4064)
			(stroke
				(width 0.1524)
				(type default)
			)
			(layer "F.SilkS")
		)
		(fp_line
			(start -0.7874 0.4064)
			(end -0.7874 -0.4064)
			(stroke
				(width 0.1524)
				(type default)
			)
			(layer "F.SilkS")
		)
		(fp_line
			(start -0.7874 -0.4064)
			(end 0.7874 -0.4064)
			(stroke
				(width 0.1524)
				(type default)
			)
			(layer "F.SilkS")
		)
		(fp_line
			(start 0.67945 0.3048)
			(end 0.120396 0.3048)
			(stroke
				(width 0.1)
				(type default)
			)
			(layer "F.Fab")
		)
		(fp_line
			(start 0.67945 -0.3048)
			(end 0.67945 0.3048)
			(stroke
				(width 0.1)
				(type default)
			)
			(layer "F.Fab")
		)
		(fp_line
			(start 0.12065 -0.2794)
			(end 0.12065 -0.3048)
			(stroke
				(width 0.1)
				(type default)
			)
			(layer "F.Fab")
		)
		(fp_line
			(start 0.12065 -0.3048)
			(end 0.67945 -0.3048)
			(stroke
				(width 0.1)
				(type default)
			)
			(layer "F.Fab")
		)
		(fp_line
			(start 0.120396 0.3048)
			(end 0.120396 0.2794)
			(stroke
				(width 0.1)
				(type default)
			)
			(layer "F.Fab")
		)
		(fp_line
			(start 0.120396 0.2794)
			(end -0.12065 0.2794)
			(stroke
				(width 0.1)
				(type default)
			)
			(layer "F.Fab")
		)
		(fp_line
			(start -0.12065 0.3048)
			(end -0.67945 0.3048)
			(stroke
				(width 0.1)
				(type default)
			)
			(layer "F.Fab")
		)
		(fp_line
			(start -0.12065 0.2794)
			(end -0.12065 0.3048)
			(stroke
				(width 0.1)
				(type default)
			)
			(layer "F.Fab")
		)
		(fp_line
			(start -0.12065 -0.2794)
			(end 0.12065 -0.2794)
			(stroke
				(width 0.1)
				(type default)
			)
			(layer "F.Fab")
		)
		(fp_line
			(start -0.12065 -0.305054)
			(end -0.12065 -0.2794)
			(stroke
				(width 0.1)
				(type default)
			)
			(layer "F.Fab")
		)
		(fp_line
			(start -0.67945 0.3048)
			(end -0.67945 -0.305054)
			(stroke
				(width 0.1)
				(type default)
			)
			(layer "F.Fab")
		)
		(fp_line
			(start -0.67945 -0.305054)
			(end -0.12065 -0.305054)
			(stroke
				(width 0.1)
				(type default)
			)
			(layer "F.Fab")
		)
		(pad "1" smd circle
			(at -0.40005 0 180)
			(size 0 0)
			(layers "F.Cu" "F.Mask" "F.Paste")
			(net "JTAG_P1_R_TRST_N")
		)
		(pad "2" smd circle
			(at 0.40005 0 180)
			(size 0 0)
			(layers "F.Cu" "F.Mask" "F.Paste")
			(net "JTAG_CPU1_TRST_N")
		)
	)
)
